# T6G (Grand Teton) — schematic netlist excerpt (pin names and nets, part order shuffled) for the footprints in the layout excerpt that follows; sources: Cadence DE-HDL packaged netlist, KiCad conversion of 04192023_DAF0TMB3IC0_F0TG_MB_C_brd_V02_OCP.brd

J27  SCONN288_DDR506112002KQ  IO  pkg DDR288S_1-1VXC  page 105
  VIN_BULK0  = P12V_MEM_CPU1
  RFU0  = NC
  VIN_MGMT  = P3V3_AUX
  HSCL  = I3C_SPD_DDRH_CPU1_SCL
  HSDA  = I3C_SPD_DDRH_CPU1_SDA
  VSS0  = GND
  DQ0_A  = M_H_CPU1_SA_DQ<0>
  VSS1  = GND
  DQ1_A  = M_H_CPU1_SA_DQ<1>
  VSS2  = GND
  DQS0_A_T  = M_H_CPU1_SA_DQS_DP<0>
  DQS0_A_C  = M_H_CPU1_SA_DQS_DN<0>
  VSS3  = GND
  DQ4_A  = M_H_CPU1_SA_DQ<4>
  VSS4  = GND
  DQ5_A  = M_H_CPU1_SA_DQ<5>
  VSS5  = GND
  DQ8_A  = M_H_CPU1_SA_DQ<8>
  VSS6  = GND
  DQ9_A  = M_H_CPU1_SA_DQ<9>
  VSS7  = GND
  DQS1_A_T  = M_H_CPU1_SA_DQS_DP<1>
  DQS1_A_C  = M_H_CPU1_SA_DQS_DN<1>
  VSS8  = GND
  DQ12_A  = M_H_CPU1_SA_DQ<12>
  VSS9  = GND
  DQ13_A  = M_H_CPU1_SA_DQ<13>
  VSS10  = GND
  DQ16_A  = M_H_CPU1_SA_DQ<16>
  VSS11  = GND
  DQ17_A  = M_H_CPU1_SA_DQ<17>
  VSS12  = GND
  DQS2_A_T  = M_H_CPU1_SA_DQS_DP<2>
  DQS2_A_C  = M_H_CPU1_SA_DQS_DN<2>
  VSS13  = GND
  DQ20_A  = M_H_CPU1_SA_DQ<20>
  VSS14  = GND
  DQ21_A  = M_H_CPU1_SA_DQ<21>
  VSS15  = GND
  DQ24_A  = M_H_CPU1_SA_DQ<24>
  VSS16  = GND
  DQ25_A  = M_H_CPU1_SA_DQ<25>
  VSS17  = GND
  DQS3_A_T  = M_H_CPU1_SA_DQS_DP<3>
  DQS3_A_C  = M_H_CPU1_SA_DQS_DN<3>
  VSS18  = GND
  DQ28_A  = M_H_CPU1_SA_DQ<28>
  VSS19  = GND
  DQ29_A  = M_H_CPU1_SA_DQ<29>
  VSS20  = GND
  CB0_A  = M_H_CPU1_SA_CB<0>
  VSS21  = GND
  CB1_A  = M_H_CPU1_SA_CB<1>
  VSS22  = GND
  DQS4_A_T  = M_H_CPU1_SA_DQS_DP<4>
  DQS4_A_C  = M_H_CPU1_SA_DQS_DN<4>
  VSS23  = GND
  CB4_A  = M_H_CPU1_SA_CB<4>
  VSS24  = GND
  CB5_A  = M_H_CPU1_SA_CB<5>
  VSS25  = GND
  ALERT_N  = M_H_CPU1_ALERT_N
  VSS26  = GND
  CS0_A_N  = M_H_CPU1_SA_CS_N<0>
  VSS27  = GND
  CA0_A  = M_H_CPU1_SA_CA<0>
  VSS28  = GND
  CA2_A  = M_H_CPU1_SA_CA<2>
  VSS29  = GND
  CA4_A  = M_H_CPU1_SA_CA<4>
  VSS30  = GND
  CA6_A  = M_H_CPU1_SA_CA<6>
  VSS31  = GND
  PAR_A  = M_H_CPU1_SA_PAR
  VSS32  = GND
  CA0_B  = M_H_CPU1_SB_CA<0>
  VSS33  = GND
  CA2_B  = M_H_CPU1_SB_CA<2>
  VSS34  = GND
  CA4_B  = M_H_CPU1_SB_CA<4>
  VSS35  = GND
  CA6_B  = M_H_CPU1_SB_CA<6>
  VSS36  = GND
  CS0_B_N  = M_H_CPU1_SB_CS_N<0>
  VSS37  = GND
  \lbd||rsp_a_n\  = M_H_CPU1_SA_RSP<0>
  \lbs||rsp_b_n\  = M_H_CPU1_SB_RSP<0>
  VSS38  = GND
  CB4_B  = M_H_CPU1_SB_CB<4>
  VSS39  = GND
  CB5_B  = M_H_CPU1_SB_CB<5>
  VSS40  = GND
  \dqs9_b_t||tdqs9_b_t||dbi4_b_n\  = M_H_CPU1_SB_DQS_DP<9>
  \dqs9_b_c||tdqs9_b_c\  = M_H_CPU1_SB_DQS_DN<9>
  VSS41  = GND
  CB0_B  = M_H_CPU1_SB_CB<0>
  VSS42  = GND
  CB1_B  = M_H_CPU1_SB_CB<1>
  VSS43  = GND
  DQ0_B  = M_H_CPU1_SB_DQ<0>
  VSS44  = GND
  DQ1_B  = M_H_CPU1_SB_DQ<1>
  VSS45  = GND
  DQS0_B_T  = M_H_CPU1_SB_DQS_DP<0>
  DQS0_B_C  = M_H_CPU1_SB_DQS_DN<0>
  VSS46  = GND
  DQ4_B  = M_H_CPU1_SB_DQ<4>
  VSS47  = GND
  DQ5_B  = M_H_CPU1_SB_DQ<5>
  VSS48  = GND
  DQ8_B  = M_H_CPU1_SB_DQ<8>
  VSS49  = GND
  DQ9_B  = M_H_CPU1_SB_DQ<9>
  VSS50  = GND
  DQS1_B_T  = M_H_CPU1_SB_DQS_DP<1>
  DQS1_B_C  = M_H_CPU1_SB_DQS_DN<1>
  VSS51  = GND
  DQ12_B  = M_H_CPU1_SB_DQ<12>
  VSS52  = GND
  DQ13_B  = M_H_CPU1_SB_DQ<13>
  VSS53  = GND
  DQ16_B  = M_H_CPU1_SB_DQ<16>
  VSS54  = GND
  DQ17_B  = M_H_CPU1_SB_DQ<17>
  VSS55  = GND
  DQS2_B_T  = M_H_CPU1_SB_DQS_DP<2>
  DQS2_B_C  = M_H_CPU1_SB_DQS_DN<2>
  VSS56  = GND
  DQ20_B  = M_H_CPU1_SB_DQ<20>
  VSS57  = GND
  DQ21_B  = M_H_CPU1_SB_DQ<21>
  VSS58  = GND
  DQ24_B  = M_H_CPU1_SB_DQ<24>
  VSS59  = GND
  DQ25_B  = M_H_CPU1_SB_DQ<25>
  VSS60  = GND
  DQS3_B_T  = M_H_CPU1_SB_DQS_DP<3>
  DQS3_B_C  = M_H_CPU1_SB_DQS_DN<3>
  VSS61  = GND
  DQ28_B  = M_H_CPU1_SB_DQ<28>
  VSS62  = GND
  DQ29_B  = M_H_CPU1_SB_DQ<29>
  VSS63  = GND
  RFU1  = NC
  VIN_BULK1  = P12V_MEM_CPU1
  VIN_BULK2  = P12V_MEM_CPU1
  \pwr_good||fail_n\  = PWRGD_CHH_CPU1_DIMM
  HAS  = PD_CHH_CPU1_DIMM_SAA
  RFU2  = NC
  RFU3  = NC
  VSS64  = GND
  DQ2_A  = M_H_CPU1_SA_DQ<2>
  VSS65  = GND
  DQ3_A  = M_H_CPU1_SA_DQ<3>
  VSS66  = GND
  \dqs5_a_c||tdqs5_a_c||dqs5_a_t||tdqs5_a_t\  = M_H_CPU1_SA_DQS_DN<5>
  \dqs5_a_t||tdqs5_a_t\  = M_H_CPU1_SA_DQS_DP<5>
  VSS67  = GND
  DQ6_A  = M_H_CPU1_SA_DQ<6>
  VSS68  = GND
  DQ7_A  = M_H_CPU1_SA_DQ<7>
  VSS69  = GND
  DQ10_A  = M_H_CPU1_SA_DQ<10>
  VSS70  = GND
  DQ11_A  = M_H_CPU1_SA_DQ<11>
  VSS71  = GND
  \dqs6_a_c||tdqs6_a_c||dqs6_a_t||tdqs6_a_t\  = M_H_CPU1_SA_DQS_DN<6>
  \dqs6_a_t||tdqs6_a_t\  = M_H_CPU1_SA_DQS_DP<6>
  VSS72  = GND
  DQ14_A  = M_H_CPU1_SA_DQ<14>
  VSS73  = GND
  DQ15_A  = M_H_CPU1_SA_DQ<15>
  VSS74  = GND
  DQ18_A  = M_H_CPU1_SA_DQ<18>
  VSS75  = GND
  DQ19_A  = M_H_CPU1_SA_DQ<19>
  VSS76  = GND
  \dqs7_a_c||tdqs7_a_c\  = M_H_CPU1_SA_DQS_DN<7>
  \dqs7_a_t||tdqs7_a_t\  = M_H_CPU1_SA_DQS_DP<7>
  VSS77  = GND
  DQ22_A  = M_H_CPU1_SA_DQ<22>
  VSS78  = GND
  DQ23_A  = M_H_CPU1_SA_DQ<23>
  VSS79  = GND
  DQ26_A  = M_H_CPU1_SA_DQ<26>
  VSS80  = GND
  DQ27_A  = M_H_CPU1_SA_DQ<27>
  VSS81  = GND
  \dqs8_a_c||tdqs8_a_c\  = M_H_CPU1_SA_DQS_DN<8>
  \dqs8_a_t||tdqs8_a_t\  = M_H_CPU1_SA_DQS_DP<8>
  VSS82  = GND
  DQ30_A  = M_H_CPU1_SA_DQ<30>
  VSS83  = GND
  DQ31_A  = M_H_CPU1_SA_DQ<31>
  VSS84  = GND
  CB2_A  = M_H_CPU1_SA_CB<2>
  VSS85  = GND
  CB3_A  = M_H_CPU1_SA_CB<3>
  VSS86  = GND
  \dqs9_a_c||tdqs9_a_c\  = M_H_CPU1_SA_DQS_DN<9>
  \dqs9_a_t||tdqs9_a_t\  = M_H_CPU1_SA_DQS_DP<9>
  VSS87  = GND
  CB6_A  = M_H_CPU1_SA_CB<6>
  VSS88  = GND
  CB7_A  = M_H_CPU1_SA_CB<7>
  VSS89  = GND
  RESET_N  = M_H_CPU1_RESET_N
  VSS90  = GND
  CS1_A_N  = M_H_CPU1_SA_CS_N<1>
  VSS91  = GND
  CA1_A  = M_H_CPU1_SA_CA<1>
  VSS92  = GND
  CA3_A  = M_H_CPU1_SA_CA<3>
  VSS93  = GND
  CA5_A  = M_H_CPU1_SA_CA<5>
  VSS94  = GND
  CK_T  = M_H_CPU1_CLK_DP<0>
  CK_C  = M_H_CPU1_CLK_DN<0>
  VSS95  = GND
  RFU4  = NC
  CA1_B  = M_H_CPU1_SB_CA<1>
  VSS96  = GND
  CA3_B  = M_H_CPU1_SB_CA<3>
  VSS97  = GND
  CA5_B  = M_H_CPU1_SB_CA<5>
  VSS98  = GND
  PAR_B  = M_H_CPU1_SB_PAR
  VSS99  = GND
  CS1_B_N  = M_H_CPU1_SB_CS_N<1>
  VSS100  = GND
  RFU5  = NC
  RFU6  = NC
  VSS101  = GND
  CB6_B  = M_H_CPU1_SB_CB<6>
  VSS102  = GND
  CB7_B  = M_H_CPU1_SB_CB<7>
  VSS103  = GND
  DQS4_B_C  = M_H_CPU1_SB_DQS_DN<4>
  DQS4_B_T  = M_H_CPU1_SB_DQS_DP<4>
  VSS104  = GND
  CB2_B  = M_H_CPU1_SB_CB<2>
  VSS105  = GND
  CB3_B  = M_H_CPU1_SB_CB<3>
  VSS106  = GND
  DQ2_B  = M_H_CPU1_SB_DQ<2>
  VSS107  = GND
  DQ3_B  = M_H_CPU1_SB_DQ<3>
  VSS108  = GND
  \dqs5_b_c||tdqs5_b_c\  = M_H_CPU1_SB_DQS_DN<5>
  \dqs5_b_t||tdqs5_b_t\  = M_H_CPU1_SB_DQS_DP<5>
  VSS109  = GND
  DQ6_B  = M_H_CPU1_SB_DQ<6>
  VSS110  = GND
  DQ7_B  = M_H_CPU1_SB_DQ<7>
  VSS111  = GND
  DQ10_B  = M_H_CPU1_SB_DQ<10>
  VSS112  = GND
  DQ11_B  = M_H_CPU1_SB_DQ<11>
  VSS113  = GND
  \dqs6_b_c||tdqs6_b_c\  = M_H_CPU1_SB_DQS_DN<6>
  \dqs6_b_t||tdqs6_b_t\  = M_H_CPU1_SB_DQS_DP<6>
  VSS114  = GND
  DQ14_B  = M_H_CPU1_SB_DQ<14>
  VSS115  = GND
  DQ15_B  = M_H_CPU1_SB_DQ<15>
  VSS116  = GND
  DQ18_B  = M_H_CPU1_SB_DQ<18>
  VSS117  = GND
  DQ19_B  = M_H_CPU1_SB_DQ<19>
  VSS118  = GND
  \dqs7_b_c||tdqs7_b_c\  = M_H_CPU1_SB_DQS_DN<7>
  \dqs7_b_t||tdqs7_b_t\  = M_H_CPU1_SB_DQS_DP<7>
  VSS119  = GND
  DQ22_B  = M_H_CPU1_SB_DQ<22>
  VSS120  = GND
  DQ23_B  = M_H_CPU1_SB_DQ<23>
  VSS121  = GND
  DQ26_B  = M_H_CPU1_SB_DQ<26>
  VSS122  = GND
  DQ27_B  = M_H_CPU1_SB_DQ<27>
  VSS123  = GND
  \dqs8_b_c||tdqs8_b_c\  = M_H_CPU1_SB_DQS_DN<8>
  \dqs8_b_t||tdqs8_b_t\  = M_H_CPU1_SB_DQS_DP<8>
  VSS124  = GND
  DQ30_B  = M_H_CPU1_SB_DQ<30>
  VSS125  = GND
  DQ31_B  = M_H_CPU1_SB_DQ<31>
  VSS126  = GND
  G1  = GND
  G2  = GND
  G3  = GND

(kicad_pcb
	(version 20260206)
	(generator "pcbnew")
	(generator_version "10.0")
	(general
		(thickness 1.6)
		(legacy_teardrops no)
	)
	(paper "A4")
	(title_block
		(title "04192023_DAF0TMB3IC0_F0TG_MB_C_brd_V02_OCP.brd")
		(comment 1 "Grand Teton / footprint 583 of 8354 (J27), pads 185-230 of 291")
	)
	(layers
		(0 "F.Cu" signal "TOP")
		(4 "In1.Cu" signal "GND")
		(6 "In2.Cu" signal "IN1")
		(8 "In3.Cu" signal "GND1")
		(10 "In4.Cu" signal "IN2")
		(12 "In5.Cu" signal "GND2")
		(14 "In6.Cu" signal "IN3")
		(16 "In7.Cu" signal "GND3")
		(18 "In8.Cu" signal "VCC")
		(20 "In9.Cu" signal "VCC1")
		(22 "In10.Cu" signal "GND4")
		(24 "In11.Cu" signal "IN4")
		(26 "In12.Cu" signal "GND5")
		(28 "In13.Cu" signal "IN5")
		(30 "In14.Cu" signal "GND6")
		(32 "In15.Cu" signal "IN6")
		(34 "In16.Cu" signal "GND7")
		(2 "B.Cu" signal "BOTTOM")
		(9 "F.Adhes" user "F.Adhesive")
		(11 "B.Adhes" user "B.Adhesive")
		(13 "F.Paste" user "Package Geometry/Pastemask Top")
		(15 "B.Paste" user "Package Geometry/Pastemask Bottom")
		(5 "F.SilkS" user "Ref Des/Silkscreen Top")
		(7 "B.SilkS" user "Ref Des/Silkscreen Bottom")
		(1 "F.Mask" user "Board Geometry/Soldermask Top")
		(3 "B.Mask" user "Board Geometry/Soldermask Bottom")
		(17 "Dwgs.User" user "User.Drawings")
		(19 "Cmts.User" user "User.Comments")
		(21 "Eco1.User" user "User.Eco1")
		(23 "Eco2.User" user "User.Eco2")
		(25 "Edge.Cuts" user "Board Geometry/Outline")
		(27 "Margin" user)
		(31 "F.CrtYd" user "Package Geometry/Place Bound Top")
		(29 "B.CrtYd" user "Package Geometry/Place Bound Bottom")
		(35 "F.Fab" user "Ref Des/Assembly Top")
		(33 "B.Fab" user "Ref Des/Assembly Bottom")
	)
	(footprint ""
		(layer "F.Cu")
		(at 174.022004 -255.560322 180)
		(property "Reference" "J27"
			(at -2.7178 -81.857088 0)
			(unlocked yes)
			(layer "F.SilkS")
			(effects
				(font
					(size 0.7874 0.5842)
					(thickness 0.1524)
				)
			)
		)
		(property "Value" ""
			(at 0 0 180)
			(layer "F.Fab")
			(effects
				(font
					(size 1.27 1.27)
				)
			)
		)
		(duplicate_pad_numbers_are_jumpers no)
		(pad "185" smd rect
			(at 2.050034 -29.325062 90)
			(size 0.519938 1.4986)
			(layers "F.Cu" "F.Mask" "F.Paste")
			(net "M_H_CPU1_SA_DQ<26>")
		)
		(pad "186" smd rect
			(at 2.050034 -28.474924 90)
			(size 0.519938 1.4986)
			(layers "F.Cu" "F.Mask" "F.Paste")
			(net "GND")
		)
		(pad "187" smd rect
			(at 2.050034 -27.62504 90)
			(size 0.519938 1.4986)
			(layers "F.Cu" "F.Mask" "F.Paste")
			(net "M_H_CPU1_SA_DQ<27>")
		)
		(pad "188" smd rect
			(at 2.050034 -26.774902 90)
			(size 0.519938 1.4986)
			(layers "F.Cu" "F.Mask" "F.Paste")
			(net "GND")
		)
		(pad "189" smd rect
			(at 2.050034 -25.925018 90)
			(size 0.519938 1.4986)
			(layers "F.Cu" "F.Mask" "F.Paste")
			(net "M_H_CPU1_SA_DQS_DN<8>")
		)
		(pad "190" smd rect
			(at 2.050034 -25.07488 90)
			(size 0.519938 1.4986)
			(layers "F.Cu" "F.Mask" "F.Paste")
			(net "M_H_CPU1_SA_DQS_DP<8>")
		)
		(pad "191" smd rect
			(at 2.050034 -24.224996 90)
			(size 0.519938 1.4986)
			(layers "F.Cu" "F.Mask" "F.Paste")
			(net "GND")
		)
		(pad "192" smd rect
			(at 2.050034 -23.375112 90)
			(size 0.519938 1.4986)
			(layers "F.Cu" "F.Mask" "F.Paste")
			(net "M_H_CPU1_SA_DQ<30>")
		)
		(pad "193" smd rect
			(at 2.050034 -22.524974 90)
			(size 0.519938 1.4986)
			(layers "F.Cu" "F.Mask" "F.Paste")
			(net "GND")
		)
		(pad "194" smd rect
			(at 2.050034 -21.67509 90)
			(size 0.519938 1.4986)
			(layers "F.Cu" "F.Mask" "F.Paste")
			(net "M_H_CPU1_SA_DQ<31>")
		)
		(pad "195" smd rect
			(at 2.050034 -20.824952 90)
			(size 0.519938 1.4986)
			(layers "F.Cu" "F.Mask" "F.Paste")
			(net "GND")
		)
		(pad "196" smd rect
			(at 2.050034 -19.975068 90)
			(size 0.519938 1.4986)
			(layers "F.Cu" "F.Mask" "F.Paste")
			(net "M_H_CPU1_SA_CB<2>")
		)
		(pad "197" smd rect
			(at 2.050034 -19.12493 90)
			(size 0.519938 1.4986)
			(layers "F.Cu" "F.Mask" "F.Paste")
			(net "GND")
		)
		(pad "198" smd rect
			(at 2.050034 -18.275046 90)
			(size 0.519938 1.4986)
			(layers "F.Cu" "F.Mask" "F.Paste")
			(net "M_H_CPU1_SA_CB<3>")
		)
		(pad "199" smd rect
			(at 2.050034 -17.424908 90)
			(size 0.519938 1.4986)
			(layers "F.Cu" "F.Mask" "F.Paste")
			(net "GND")
		)
		(pad "200" smd rect
			(at 2.050034 -16.575024 90)
			(size 0.519938 1.4986)
			(layers "F.Cu" "F.Mask" "F.Paste")
			(net "M_H_CPU1_SA_DQS_DN<9>")
		)
		(pad "201" smd rect
			(at 2.050034 -15.724886 90)
			(size 0.519938 1.4986)
			(layers "F.Cu" "F.Mask" "F.Paste")
			(net "M_H_CPU1_SA_DQS_DP<9>")
		)
		(pad "202" smd rect
			(at 2.050034 -14.875002 90)
			(size 0.519938 1.4986)
			(layers "F.Cu" "F.Mask" "F.Paste")
			(net "GND")
		)
		(pad "203" smd rect
			(at 2.050034 -14.025118 90)
			(size 0.519938 1.4986)
			(layers "F.Cu" "F.Mask" "F.Paste")
			(net "M_H_CPU1_SA_CB<6>")
		)
		(pad "204" smd rect
			(at 2.050034 -13.17498 90)
			(size 0.519938 1.4986)
			(layers "F.Cu" "F.Mask" "F.Paste")
			(net "GND")
		)
		(pad "205" smd rect
			(at 2.050034 -12.325096 90)
			(size 0.519938 1.4986)
			(layers "F.Cu" "F.Mask" "F.Paste")
			(net "M_H_CPU1_SA_CB<7>")
		)
		(pad "206" smd rect
			(at 2.050034 -11.474958 90)
			(size 0.519938 1.4986)
			(layers "F.Cu" "F.Mask" "F.Paste")
			(net "GND")
		)
		(pad "207" smd rect
			(at 2.050034 -10.625074 90)
			(size 0.519938 1.4986)
			(layers "F.Cu" "F.Mask" "F.Paste")
			(net "M_H_CPU1_RESET_N")
		)
		(pad "208" smd rect
			(at 2.050034 -9.774936 90)
			(size 0.519938 1.4986)
			(layers "F.Cu" "F.Mask" "F.Paste")
			(net "GND")
		)
		(pad "209" smd rect
			(at 2.050034 -8.925052 90)
			(size 0.519938 1.4986)
			(layers "F.Cu" "F.Mask" "F.Paste")
			(net "M_H_CPU1_SA_CS_N<1>")
		)
		(pad "210" smd rect
			(at 2.050034 -8.074914 90)
			(size 0.519938 1.4986)
			(layers "F.Cu" "F.Mask" "F.Paste")
			(net "GND")
		)
		(pad "211" smd rect
			(at 2.050034 -7.22503 90)
			(size 0.519938 1.4986)
			(layers "F.Cu" "F.Mask" "F.Paste")
			(net "M_H_CPU1_SA_CA<1>")
		)
		(pad "212" smd rect
			(at 2.050034 -6.374892 90)
			(size 0.519938 1.4986)
			(layers "F.Cu" "F.Mask" "F.Paste")
			(net "GND")
		)
		(pad "213" smd rect
			(at 2.050034 -5.525008 90)
			(size 0.519938 1.4986)
			(layers "F.Cu" "F.Mask" "F.Paste")
			(net "M_H_CPU1_SA_CA<3>")
		)
		(pad "214" smd rect
			(at 2.050034 -4.675124 90)
			(size 0.519938 1.4986)
			(layers "F.Cu" "F.Mask" "F.Paste")
			(net "GND")
		)
		(pad "215" smd rect
			(at 2.050034 -3.824986 90)
			(size 0.519938 1.4986)
			(layers "F.Cu" "F.Mask" "F.Paste")
			(net "M_H_CPU1_SA_CA<5>")
		)
		(pad "216" smd rect
			(at 2.050034 -2.975102 90)
			(size 0.519938 1.4986)
			(layers "F.Cu" "F.Mask" "F.Paste")
			(net "GND")
		)
		(pad "217" smd rect
			(at 2.050034 -2.124964 90)
			(size 0.519938 1.4986)
			(layers "F.Cu" "F.Mask" "F.Paste")
			(net "M_H_CPU1_CLK_DP<0>")
		)
		(pad "218" smd rect
			(at 2.050034 -1.27508 90)
			(size 0.519938 1.4986)
			(layers "F.Cu" "F.Mask" "F.Paste")
			(net "M_H_CPU1_CLK_DN<0>")
		)
		(pad "219" smd rect
			(at 2.050034 -0.424942 90)
			(size 0.519938 1.4986)
			(layers "F.Cu" "F.Mask" "F.Paste")
			(net "GND")
		)
		(pad "220" smd rect
			(at 2.050034 5.525008 90)
			(size 0.519938 1.4986)
			(layers "F.Cu" "F.Mask" "F.Paste")
			(net "Net_2358")
		)
		(pad "221" smd rect
			(at 2.050034 6.374892 90)
			(size 0.519938 1.4986)
			(layers "F.Cu" "F.Mask" "F.Paste")
			(net "M_H_CPU1_SB_CA<1>")
		)
		(pad "222" smd rect
			(at 2.050034 7.22503 90)
			(size 0.519938 1.4986)
			(layers "F.Cu" "F.Mask" "F.Paste")
			(net "GND")
		)
		(pad "223" smd rect
			(at 2.050034 8.074914 90)
			(size 0.519938 1.4986)
			(layers "F.Cu" "F.Mask" "F.Paste")
			(net "M_H_CPU1_SB_CA<3>")
		)
		(pad "224" smd rect
			(at 2.050034 8.925052 90)
			(size 0.519938 1.4986)
			(layers "F.Cu" "F.Mask" "F.Paste")
			(net "GND")
		)
		(pad "225" smd rect
			(at 2.050034 9.774936 90)
			(size 0.519938 1.4986)
			(layers "F.Cu" "F.Mask" "F.Paste")
			(net "M_H_CPU1_SB_CA<5>")
		)
		(pad "226" smd rect
			(at 2.050034 10.625074 90)
			(size 0.519938 1.4986)
			(layers "F.Cu" "F.Mask" "F.Paste")
			(net "GND")
		)
		(pad "227" smd rect
			(at 2.050034 11.474958 90)
			(size 0.519938 1.4986)
			(layers "F.Cu" "F.Mask" "F.Paste")
			(net "M_H_CPU1_SB_PAR")
		)
		(pad "228" smd rect
			(at 2.050034 12.325096 90)
			(size 0.519938 1.4986)
			(layers "F.Cu" "F.Mask" "F.Paste")
			(net "GND")
		)
		(pad "229" smd rect
			(at 2.050034 13.17498 90)
			(size 0.519938 1.4986)
			(layers "F.Cu" "F.Mask" "F.Paste")
			(net "M_H_CPU1_SB_CS_N<1>")
		)
		(pad "230" smd rect
			(at 2.050034 14.025118 90)
			(size 0.519938 1.4986)
			(layers "F.Cu" "F.Mask" "F.Paste")
			(net "GND")
		)
	)
)
